G04*
G04 #@! TF.GenerationSoftware,Altium Limited,Altium Designer,23.6.0 (18)*
G04*
G04 Layer_Color=128*
%FSLAX44Y44*%
%MOMM*%
G71*
G04*
G04 #@! TF.SameCoordinates,59133E90-4310-4D8A-9E2C-91A8D2F69FBB*
G04*
G04*
G04 #@! TF.FilePolarity,Positive*
G04*
G01*
G75*
%ADD60R,0.3500X1.9500*%
D60*
X140060Y15250D02*
D03*
X135060D02*
D03*
X130060D02*
D03*
X125060D02*
D03*
X120060D02*
D03*
X115060D02*
D03*
X110060D02*
D03*
X155060D02*
D03*
X150060D02*
D03*
X80060D02*
D03*
X90060D02*
D03*
X85060D02*
D03*
X95060D02*
D03*
X75060D02*
D03*
X70060D02*
D03*
X65060D02*
D03*
X60060D02*
D03*
X55060D02*
D03*
X50060D02*
D03*
X45060D02*
D03*
X40060D02*
D03*
X35060D02*
D03*
X30060D02*
D03*
X25060D02*
D03*
X100060D02*
D03*
X105060D02*
D03*
X145060D02*
D03*
X185060D02*
D03*
X200060D02*
D03*
X195060D02*
D03*
X190060D02*
D03*
X180060D02*
D03*
X20060D02*
D03*
M02*
